(kicad_pcb
	(version 20241229)
	(generator "pcbnew")
	(generator_version "9.0")
	(general
		(thickness 1.711)
		(legacy_teardrops no)
	)
	(paper "A4")
	(title_block
		(title "Antmicro Baseboard for Jetson AGX Thor")
		(date "2026-02-18")
		(rev "1.1.0")
		(company "Antmicro Ltd")
		(comment 1 "www.antmicro.com")
		(comment 9 "footprints 1141-1144 of 1170")
	)
	(layers
		(0 "F.Cu" signal)
		(4 "In1.Cu" signal)
		(6 "In2.Cu" signal)
		(8 "In3.Cu" signal)
		(10 "In4.Cu" jumper)
		(12 "In5.Cu" signal)
		(14 "In6.Cu" signal)
		(16 "In7.Cu" signal)
		(18 "In8.Cu" signal)
		(2 "B.Cu" signal)
		(9 "F.Adhes" user "F.Adhesive")
		(11 "B.Adhes" user "B.Adhesive")
		(13 "F.Paste" user)
		(15 "B.Paste" user)
		(5 "F.SilkS" user "F.Silkscreen")
		(7 "B.SilkS" user "B.Silkscreen")
		(1 "F.Mask" user)
		(3 "B.Mask" user)
		(17 "Dwgs.User" user "User.Drawings")
		(19 "Cmts.User" user "User.Comments")
		(21 "Eco1.User" user "User.Eco1")
		(23 "Eco2.User" user "User.Eco2")
		(25 "Edge.Cuts" user)
		(27 "Margin" user)
		(31 "F.CrtYd" user "F.Courtyard")
		(29 "B.CrtYd" user "B.Courtyard")
		(35 "F.Fab" user)
		(33 "B.Fab" user)
	)
	(footprint "antmicro-footprints:LED_0603_1608Metric_G"
		(layer "B.Cu")
		(at 113.47 116.59)
		(descr "LED SMD 0603 Green")
		(tags "LED SMD 0603 Green")
		(property "Reference" "D32"
			(at 3.33 -0.39 0)
			(layer "B.SilkS")
			(effects
				(font
					(size 0.7 0.7)
					(thickness 0.15)
				)
				(justify right top mirror)
			)
		)
		(property "Value" "LED_G_0603_LTST-C190GKT"
			(at -0.001 -1.599 0)
			(layer "B.Fab")
			(effects
				(font
					(size 0.7 0.7)
					(thickness 0.15)
				)
				(justify right top mirror)
			)
		)
		(property "Datasheet" "https://media.digikey.com/pdf/Data%20Sheets/Lite-On%20PDFs/LTST-C190GKT.pdf"
			(at 0 0 0)
			(layer "B.Fab")
			(hide yes)
			(effects
				(font
					(size 1.27 1.27)
					(thickness 0.15)
				)
				(justify mirror)
			)
		)
		(property "Description" "LED, Green, SMD, 0603, 20 mA, 2.1 V, 569 nm"
			(at 0 0 0)
			(layer "B.Fab")
			(hide yes)
			(effects
				(font
					(size 1.27 1.27)
					(thickness 0.15)
				)
				(justify mirror)
			)
		)
		(property "MPN" "LTST-C190GKT"
			(at 0 0 180)
			(unlocked yes)
			(layer "B.Fab")
			(hide yes)
			(effects
				(font
					(size 1 1)
					(thickness 0.15)
				)
				(justify mirror)
			)
		)
		(property "Manufacturer" "Lite-On"
			(at 0 0 180)
			(unlocked yes)
			(layer "B.Fab")
			(hide yes)
			(effects
				(font
					(size 1 1)
					(thickness 0.15)
				)
				(justify mirror)
			)
		)
		(property "Author" "Antmicro"
			(at 0 0 180)
			(unlocked yes)
			(layer "B.Fab")
			(hide yes)
			(effects
				(font
					(size 1 1)
					(thickness 0.15)
				)
				(justify mirror)
			)
		)
		(property "License" "Apache-2.0"
			(at 0 0 180)
			(unlocked yes)
			(layer "B.Fab")
			(hide yes)
			(effects
				(font
					(size 1 1)
					(thickness 0.15)
				)
				(justify mirror)
			)
		)
		(property "Color" "Green"
			(at 0 0 180)
			(unlocked yes)
			(layer "B.Fab")
			(hide yes)
			(effects
				(font
					(size 1 1)
					(thickness 0.15)
				)
				(justify mirror)
			)
		)
		(sheetname "/M.2/")
		(sheetfile "m2.kicad_sch")
		(attr smd)
		(fp_line
			(start -1.18 0.319)
			(end -1.18 -0.321)
			(stroke
				(width 0.15)
				(type solid)
			)
			(layer "B.SilkS")
		)
		(fp_line
			(start -0.094672 -0.201008)
			(end -0.094672 0.198992)
			(stroke
				(width 0.1)
				(type solid)
			)
			(layer "B.SilkS")
		)
		(fp_line
			(start -0.094672 -0.001008)
			(end -0.24 -0.001008)
			(stroke
				(width 0.1)
				(type solid)
			)
			(layer "B.SilkS")
		)
		(fp_line
			(start -0.094672 -0.001008)
			(end 0.105328 0.198992)
			(stroke
				(width 0.1)
				(type solid)
			)
			(layer "B.SilkS")
		)
		(fp_line
			(start 0.105328 -0.201008)
			(end -0.094672 -0.001008)
			(stroke
				(width 0.1)
				(type solid)
			)
			(layer "B.SilkS")
		)
		(fp_line
			(start 0.105328 -0.201008)
			(end 0.105328 0.198992)
			(stroke
				(width 0.1)
				(type solid)
			)
			(layer "B.SilkS")
		)
		(fp_line
			(start 0.105328 -0.001008)
			(end 0.24 -0.001)
			(stroke
				(width 0.1)
				(type solid)
			)
			(layer "B.SilkS")
		)
		(fp_line
			(start 0.22 -0.35)
			(end -0.22 -0.35)
			(stroke
				(width 0.15)
				(type solid)
			)
			(layer "B.SilkS")
		)
		(fp_line
			(start 0.22 0.35)
			(end -0.22 0.35)
			(stroke
				(width 0.15)
				(type solid)
			)
			(layer "B.SilkS")
		)
		(fp_rect
			(start 1.25 -0.65)
			(end -1.25 0.65)
			(stroke
				(width 0.05)
				(type solid)
			)
			(fill no)
			(layer "B.CrtYd")
		)
		(fp_line
			(start -0.199 -0.2)
			(end -0.199 -0.1)
			(stroke
				(width 0.15)
				(type solid)
			)
			(layer "B.Fab")
		)
		(fp_line
			(start -0.199 0)
			(end -0.597 0)
			(stroke
				(width 0.15)
				(type solid)
			)
			(layer "B.Fab")
		)
		(fp_line
			(start -0.199 0.202)
			(end -0.199 -0.1)
			(stroke
				(width 0.15)
				(type solid)
			)
			(layer "B.Fab")
		)
		(fp_line
			(start -0.101 0)
			(end 0.201 -0.2)
			(stroke
				(width 0.15)
				(type solid)
			)
			(layer "B.Fab")
		)
		(fp_line
			(start 0.201 -0.2)
			(end 0.201 0)
			(stroke
				(width 0.15)
				(type solid)
			)
			(layer "B.Fab")
		)
		(fp_line
			(start 0.201 0)
			(end 0.201 0.202)
			(stroke
				(width 0.15)
				(type solid)
			)
			(layer "B.Fab")
		)
		(fp_line
			(start 0.201 0.202)
			(end -0.101 0)
			(stroke
				(width 0.15)
				(type solid)
			)
			(layer "B.Fab")
		)
		(fp_line
			(start 0.599 0)
			(end 0.201 0)
			(stroke
				(width 0.15)
				(type solid)
			)
			(layer "B.Fab")
		)
		(fp_rect
			(start 0.848 -0.4)
			(end -0.85 0.402)
			(stroke
				(width 0.15)
				(type solid)
			)
			(fill no)
			(layer "B.Fab")
		)
		(fp_text user "License: Apache-2.0"
			(at -1.4224 -3.599 0)
			(layer "B.Fab")
			(effects
				(font
					(size 0.7 0.7)
					(thickness 0.15)
				)
				(justify right top mirror)
			)
		)
		(fp_text user "${REFERENCE}"
			(at -1.4224 -5.999 0)
			(layer "B.Fab")
			(effects
				(font
					(size 0.7 0.7)
					(thickness 0.15)
				)
				(justify right top mirror)
			)
		)
		(fp_text user "Author: Antmicro"
			(at -1.4224 -4.799 0)
			(layer "B.Fab")
			(effects
				(font
					(size 0.7 0.7)
					(thickness 0.15)
				)
				(justify right top mirror)
			)
		)
		(pad "1" smd roundrect
			(at -0.7 0 180)
			(size 0.8 1)
			(layers "B.Cu" "B.Mask" "B.Paste")
			(roundrect_rratio 0.2)
			(net 33 "Net-(D32-C)")
			(pinfunction "C")
			(pintype "passive")
		)
		(pad "2" smd roundrect
			(at 0.7 0 180)
			(size 0.8 1)
			(layers "B.Cu" "B.Mask" "B.Paste")
			(roundrect_rratio 0.2)
			(net 544 "Net-(D32-A)")
			(pinfunction "A")
			(pintype "passive")
		)
	)
	(footprint "antmicro-footprints:R_0402_1005Metric"
		(layer "B.Cu")
		(at 238.1 81.45 180)
		(descr "Resistor SMD 0402")
		(tags "resistor SMD 0402")
		(property "Reference" "R151"
			(at -1.535 2.745 0)
			(layer "B.SilkS")
			(effects
				(font
					(size 0.7 0.7)
					(thickness 0.15)
				)
				(justify left bottom mirror)
			)
		)
		(property "Value" "R_0R_0402"
			(at -1.011843 -1.772046 0)
			(layer "B.Fab")
			(effects
				(font
					(size 0.7 0.7)
					(thickness 0.15)
				)
				(justify left bottom mirror)
			)
		)
		(property "Datasheet" "https://industrial.panasonic.com/cdbs/www-data/pdf/RDA0000/AOA0000C301.pdf"
			(at 0 0 0)
			(layer "B.Fab")
			(hide yes)
			(effects
				(font
					(size 1.27 1.27)
					(thickness 0.15)
				)
				(justify mirror)
			)
		)
		(property "Description" "SMD Chip Resistor, Jumper, 0 ohm, 100 mW, 0402 [1005 Metric], Thick Film, General Purpose"
			(at 0 0 0)
			(layer "B.Fab")
			(hide yes)
			(effects
				(font
					(size 1.27 1.27)
					(thickness 0.15)
				)
				(justify mirror)
			)
		)
		(property "Manufacturer" "Panasonic"
			(at 0 0 0)
			(unlocked yes)
			(layer "B.Fab")
			(hide yes)
			(effects
				(font
					(size 1 1)
					(thickness 0.15)
				)
				(justify mirror)
			)
		)
		(property "MPN" "ERJ2GE0R00X"
			(at 0 0 0)
			(unlocked yes)
			(layer "B.Fab")
			(hide yes)
			(effects
				(font
					(size 1 1)
					(thickness 0.15)
				)
				(justify mirror)
			)
		)
		(property "Val" "0R"
			(at 0 0 0)
			(unlocked yes)
			(layer "B.Fab")
			(hide yes)
			(effects
				(font
					(size 1 1)
					(thickness 0.15)
				)
				(justify mirror)
			)
		)
		(property "License" "Apache-2.0"
			(at 0 0 0)
			(unlocked yes)
			(layer "B.Fab")
			(hide yes)
			(effects
				(font
					(size 1 1)
					(thickness 0.15)
				)
				(justify mirror)
			)
		)
		(property "Author" "Antmicro"
			(at 0 0 0)
			(unlocked yes)
			(layer "B.Fab")
			(hide yes)
			(effects
				(font
					(size 1 1)
					(thickness 0.15)
				)
				(justify mirror)
			)
		)
		(property "Tolerance" "~"
			(at 0 0 0)
			(unlocked yes)
			(layer "B.Fab")
			(hide yes)
			(effects
				(font
					(size 1 1)
					(thickness 0.15)
				)
				(justify mirror)
			)
		)
		(property "Current" "1A"
			(at 0 0 0)
			(unlocked yes)
			(layer "B.Fab")
			(hide yes)
			(effects
				(font
					(size 1 1)
					(thickness 0.15)
				)
				(justify mirror)
			)
		)
		(sheetname "/USB Debug, PD/")
		(sheetfile "usb_debug_pd.kicad_sch")
		(attr smd)
		(fp_poly
			(pts
				(xy -0.925 0.47) (xy -0.925 -0.47) (xy 0.925 -0.47) (xy 0.925 0.47)
			)
			(stroke
				(width 0.05)
				(type default)
			)
			(fill no)
			(layer "B.CrtYd")
		)
		(fp_poly
			(pts
				(xy -0.5 0.25) (xy -0.5 -0.25) (xy 0.5 -0.25) (xy 0.5 0.25)
			)
			(stroke
				(width 0.15)
				(type solid)
			)
			(fill no)
			(layer "B.Fab")
		)
		(fp_text user "Author: Antmicro"
			(at -0.95 -4.169 0)
			(layer "B.Fab")
			(effects
				(font
					(size 0.7 0.7)
					(thickness 0.15)
				)
				(justify left bottom mirror)
			)
		)
		(fp_text user "${REFERENCE}"
			(at -0.95 -3.168 0)
			(layer "B.Fab")
			(effects
				(font
					(size 0.7 0.7)
					(thickness 0.15)
				)
				(justify left bottom mirror)
			)
		)
		(fp_text user "License: Apache-2.0"
			(at -0.949999 -5.169 0)
			(layer "B.Fab")
			(effects
				(font
					(size 0.7 0.7)
					(thickness 0.15)
				)
				(justify left bottom mirror)
			)
		)
		(pad "1" smd roundrect
			(at -0.48 0 180)
			(size 0.59 0.64)
			(layers "B.Cu" "B.Mask" "B.Paste")
			(roundrect_rratio 0.25)
			(net 975 "/USB Debug, PD/USBC0_5V_PEN")
			(pintype "passive")
		)
		(pad "2" smd roundrect
			(at 0.48 0 180)
			(size 0.59 0.64)
			(layers "B.Cu" "B.Mask" "B.Paste")
			(roundrect_rratio 0.25)
			(net 977 "Net-(U40-EN)")
			(pintype "passive")
		)
	)
	(footprint "antmicro-footprints:SOT-523"
		(layer "B.Cu")
		(at 213.798 78.007 -90)
		(property "Reference" "Q3"
			(at -0.807 -2.102 90)
			(layer "B.SilkS")
			(effects
				(font
					(size 0.7 0.7)
					(thickness 0.15)
				)
				(justify left bottom mirror)
			)
		)
		(property "Value" "DMG1012T-7"
			(at 0.1 -1.824 90)
			(layer "B.Fab")
			(effects
				(font
					(size 0.7 0.7)
					(thickness 0.15)
				)
				(justify left bottom mirror)
			)
		)
		(property "Datasheet" "https://www.diodes.com/assets/Datasheets/ds31783.pdf"
			(at 0 0 90)
			(layer "B.Fab")
			(hide yes)
			(effects
				(font
					(size 1.27 1.27)
					(thickness 0.15)
				)
				(justify mirror)
			)
		)
		(property "Description" "Power MOSFET, N Channel, 20 V, 630 mA, 0.3 ohm, SOT-523, Surface Mount"
			(at 0 0 90)
			(layer "B.Fab")
			(hide yes)
			(effects
				(font
					(size 1.27 1.27)
					(thickness 0.15)
				)
				(justify mirror)
			)
		)
		(property "MPN" "DMG1012T-7"
			(at 0 0 90)
			(unlocked yes)
			(layer "B.Fab")
			(hide yes)
			(effects
				(font
					(size 1 1)
					(thickness 0.15)
				)
				(justify mirror)
			)
		)
		(property "Manufacturer" "Diodes Incorporated"
			(at 0 0 90)
			(unlocked yes)
			(layer "B.Fab")
			(hide yes)
			(effects
				(font
					(size 1 1)
					(thickness 0.15)
				)
				(justify mirror)
			)
		)
		(property "Author" "Antmicro"
			(at 0 0 90)
			(unlocked yes)
			(layer "B.Fab")
			(hide yes)
			(effects
				(font
					(size 1 1)
					(thickness 0.15)
				)
				(justify mirror)
			)
		)
		(property "License" "Apache-2.0"
			(at 0 0 90)
			(unlocked yes)
			(layer "B.Fab")
			(hide yes)
			(effects
				(font
					(size 1 1)
					(thickness 0.15)
				)
				(justify mirror)
			)
		)
		(sheetname "/USB Debug, PD/")
		(sheetfile "usb_debug_pd.kicad_sch")
		(attr smd)
		(fp_line
			(start -0.725 0.551)
			(end -0.277 0.551)
			(stroke
				(width 0.15)
				(type solid)
			)
			(layer "B.SilkS")
		)
		(fp_line
			(start -0.277 0.551)
			(end -0.277 0.75)
			(stroke
				(width 0.15)
				(type solid)
			)
			(layer "B.SilkS")
		)
		(fp_line
			(start -0.927 0.351)
			(end -0.725 0.551)
			(stroke
				(width 0.15)
				(type solid)
			)
			(layer "B.SilkS")
		)
		(fp_line
			(start -0.927 0.051)
			(end -0.927 0.351)
			(stroke
				(width 0.15)
				(type solid)
			)
			(layer "B.SilkS")
		)
		(fp_circle
			(center -0.9652 -0.9652)
			(end -0.9152 -0.9652)
			(stroke
				(width 0.15)
				(type solid)
			)
			(fill yes)
			(layer "B.SilkS")
		)
		(fp_line
			(start -1.12 1.16)
			(end 1.1 1.16)
			(stroke
				(width 0.05)
				(type solid)
			)
			(layer "B.CrtYd")
		)
		(fp_line
			(start -1.12 1.16)
			(end -1.12 -1.15)
			(stroke
				(width 0.05)
				(type solid)
			)
			(layer "B.CrtYd")
		)
		(fp_line
			(start 1.1 1.16)
			(end 1.1 -1.15)
			(stroke
				(width 0.05)
				(type solid)
			)
			(layer "B.CrtYd")
		)
		(fp_line
			(start -1.12 -1.15)
			(end 1.1 -1.15)
			(stroke
				(width 0.05)
				(type solid)
			)
			(layer "B.CrtYd")
		)
		(fp_line
			(start -0.652 0.425)
			(end -0.802 0.276)
			(stroke
				(width 0.15)
				(type solid)
			)
			(layer "B.Fab")
		)
		(fp_line
			(start 0.8 0.425)
			(end -0.652 0.425)
			(stroke
				(width 0.15)
				(type solid)
			)
			(layer "B.Fab")
		)
		(fp_line
			(start 0.8 0.425)
			(end 0.8 -0.424)
			(stroke
				(width 0.15)
				(type solid)
			)
			(layer "B.Fab")
		)
		(fp_line
			(start -0.802 0.276)
			(end -0.802 -0.424)
			(stroke
				(width 0.15)
				(type solid)
			)
			(layer "B.Fab")
		)
		(fp_line
			(start 0.8 -0.424)
			(end -0.802 -0.424)
			(stroke
				(width 0.15)
				(type solid)
			)
			(layer "B.Fab")
		)
		(fp_circle
			(center -0.9652 -0.9652)
			(end -0.9144 -0.9652)
			(stroke
				(width 0.15)
				(type solid)
			)
			(fill no)
			(layer "B.Fab")
		)
		(fp_text user "Author: Antmicro"
			(at -1.12 -6.224 90)
			(layer "B.Fab")
			(effects
				(font
					(size 0.7 0.7)
					(thickness 0.15)
				)
				(justify left bottom mirror)
			)
		)
		(fp_text user "License: Apache-2.0"
			(at -1.12 -5.024 90)
			(layer "B.Fab")
			(effects
				(font
					(size 0.7 0.7)
					(thickness 0.15)
				)
				(justify left bottom mirror)
			)
		)
		(fp_text user "${REFERENCE}"
			(at -1.12 -3.824 90)
			(layer "B.Fab")
			(effects
				(font
					(size 0.7 0.7)
					(thickness 0.15)
				)
				(justify left bottom mirror)
			)
		)
		(pad "1" smd rect
			(at -0.5 -0.65 270)
			(size 0.4 0.51)
			(layers "B.Cu" "B.Mask" "B.Paste")
			(net 104 "/M.2/~{PEWAKE}")
			(pinfunction "G")
			(pintype "input")
		)
		(pad "2" smd rect
			(at 0.498 -0.65 270)
			(size 0.4 0.51)
			(layers "B.Cu" "B.Mask" "B.Paste")
			(net 1 "GND")
			(pinfunction "S")
			(pintype "passive")
		)
		(pad "3" smd rect
			(at 0 0.652 270)
			(size 0.4 0.51)
			(layers "B.Cu" "B.Mask" "B.Paste")
			(net 881 "/USB Debug, PD/FTDI_CBUS_EN")
			(pinfunction "D")
			(pintype "passive")
		)
	)
	(footprint "antmicro-footprints:C_0402_1005Metric"
		(layer "B.Cu")
		(at 198.476 144 -90)
		(descr "Capacitor SMD 0402")
		(tags "capacitor SMD 0402")
		(property "Reference" "C180"
			(at -1.8 0.65 90)
			(layer "B.SilkS")
			(effects
				(font
					(size 0.7 0.7)
					(thickness 0.15)
				)
				(justify left bottom mirror)
			)
		)
		(property "Value" "C_100n_0402"
			(at -1.022927 -2.155213 90)
			(layer "B.Fab")
			(effects
				(font
					(size 0.7 0.7)
					(thickness 0.15)
				)
				(justify left bottom mirror)
			)
		)
		(property "Datasheet" "https://www.murata.com/products/productdetail?partno=GRM155R61H104KE14%23"
			(at 0 0 90)
			(layer "B.Fab")
			(hide yes)
			(effects
				(font
					(size 1.27 1.27)
					(thickness 0.15)
				)
				(justify mirror)
			)
		)
		(property "Description" "SMD Multilayer Ceramic Capacitor, 0.1 µF, 50 V, 0402 [1005 Metric], ± 10%, X5R, GRM Series"
			(at 0 0 90)
			(layer "B.Fab")
			(hide yes)
			(effects
				(font
					(size 1.27 1.27)
					(thickness 0.15)
				)
				(justify mirror)
			)
		)
		(property "MPN" "GRM155R61H104KE14D"
			(at 0 0 90)
			(unlocked yes)
			(layer "B.Fab")
			(hide yes)
			(effects
				(font
					(size 1 1)
					(thickness 0.15)
				)
				(justify mirror)
			)
		)
		(property "Manufacturer" "Murata"
			(at 0 0 90)
			(unlocked yes)
			(layer "B.Fab")
			(hide yes)
			(effects
				(font
					(size 1 1)
					(thickness 0.15)
				)
				(justify mirror)
			)
		)
		(property "License" "Apache-2.0"
			(at 0 0 90)
			(unlocked yes)
			(layer "B.Fab")
			(hide yes)
			(effects
				(font
					(size 1 1)
					(thickness 0.15)
				)
				(justify mirror)
			)
		)
		(property "Author" "Antmicro"
			(at 0 0 90)
			(unlocked yes)
			(layer "B.Fab")
			(hide yes)
			(effects
				(font
					(size 1 1)
					(thickness 0.15)
				)
				(justify mirror)
			)
		)
		(property "Val" "100n"
			(at 0 0 90)
			(unlocked yes)
			(layer "B.Fab")
			(hide yes)
			(effects
				(font
					(size 1 1)
					(thickness 0.15)
				)
				(justify mirror)
			)
		)
		(property "Voltage" "50V"
			(at 0 0 90)
			(unlocked yes)
			(layer "B.Fab")
			(hide yes)
			(effects
				(font
					(size 1 1)
					(thickness 0.15)
				)
				(justify mirror)
			)
		)
		(property "Dielectric" "X5R"
			(at 0 0 90)
			(unlocked yes)
			(layer "B.Fab")
			(hide yes)
			(effects
				(font
					(size 1 1)
					(thickness 0.15)
				)
				(justify mirror)
			)
		)
		(sheetname "/SFP/")
		(sheetfile "sfp.kicad_sch")
		(attr smd)
		(fp_poly
			(pts
				(xy -0.925 0.47) (xy 0.925 0.47) (xy 0.925 -0.47) (xy -0.925 -0.47)
			)
			(stroke
				(width 0.05)
				(type default)
			)
			(fill no)
			(layer "B.CrtYd")
		)
		(fp_line
			(start -0.494 0.25)
			(end 0.504 0.25)
			(stroke
				(width 0.15)
				(type solid)
			)
			(layer "B.Fab")
		)
		(fp_line
			(start 0.504 0.25)
			(end 0.504 -0.248)
			(stroke
				(width 0.15)
				(type solid)
			)
			(layer "B.Fab")
		)
		(fp_line
			(start -0.494 -0.248)
			(end -0.494 0.25)
			(stroke
				(width 0.15)
				(type solid)
			)
			(layer "B.Fab")
		)
		(fp_line
			(start 0.504 -0.248)
			(end -0.494 -0.248)
			(stroke
				(width 0.15)
				(type solid)
			)
			(layer "B.Fab")
		)
		(fp_text user "License: Apache-2.0"
			(at -0.939 -5.799 90)
			(layer "B.Fab")
			(effects
				(font
					(size 0.7 0.7)
					(thickness 0.15)
				)
				(justify left bottom mirror)
			)
		)
		(fp_text user "Author: Antmicro"
			(at -0.939 -3.399 90)
			(layer "B.Fab")
			(effects
				(font
					(size 0.7 0.7)
					(thickness 0.15)
				)
				(justify left bottom mirror)
			)
		)
		(fp_text user "${REFERENCE}"
			(at -0.939 -4.599 90)
			(layer "B.Fab")
			(effects
				(font
					(size 0.7 0.7)
					(thickness 0.15)
				)
				(justify left bottom mirror)
			)
		)
		(pad "1" smd roundrect
			(at -0.48 0 270)
			(size 0.59 0.64)
			(layers "B.Cu" "B.Mask" "B.Paste")
			(roundrect_rratio 0.25)
			(net 1 "GND")
			(pintype "passive")
		)
		(pad "2" smd roundrect
			(at 0.48 0 270)
			(size 0.59 0.64)
			(layers "B.Cu" "B.Mask" "B.Paste")
			(roundrect_rratio 0.25)
			(net 2 "+3V3")
			(pintype "passive")
		)
	)
)
